(kicad_pcb
	(version 20260206)
	(generator "pcbnew")
	(generator_version "10.0")
	(general
		(thickness 1.6)
		(legacy_teardrops no)
	)
	(paper "A4")
	(title_block
		(title "Bryce Canyon_F.DPB_16315-1-OCP.brd")
		(comment 1 "Bryce Canyon / footprints 403-405 of 2223")
	)
	(layers
		(0 "F.Cu" signal "TOP")
		(4 "In1.Cu" signal "L2GND")
		(6 "In2.Cu" signal "L3")
		(8 "In3.Cu" signal "L4GND")
		(10 "In4.Cu" signal "L5")
		(12 "In5.Cu" signal "L6VCC")
		(14 "In6.Cu" signal "L7VCC")
		(16 "In7.Cu" signal "L8")
		(18 "In8.Cu" signal "L9GND")
		(20 "In9.Cu" signal "L10")
		(22 "In10.Cu" signal "L11GND")
		(2 "B.Cu" signal "BOTTOM")
		(9 "F.Adhes" user "F.Adhesive")
		(11 "B.Adhes" user "B.Adhesive")
		(13 "F.Paste" user "Package Geometry/Pastemask Top")
		(15 "B.Paste" user "Package Geometry/Pastemask Bottom")
		(5 "F.SilkS" user "Ref Des/Silkscreen Top")
		(7 "B.SilkS" user "Ref Des/Silkscreen Bottom")
		(1 "F.Mask" user "Board Geometry/Soldermask Top")
		(3 "B.Mask" user "Board Geometry/Soldermask Bottom")
		(17 "Dwgs.User" user "User.Drawings")
		(19 "Cmts.User" user "User.Comments")
		(21 "Eco1.User" user "User.Eco1")
		(23 "Eco2.User" user "User.Eco2")
		(25 "Edge.Cuts" user "Board Geometry/Outline")
		(27 "Margin" user)
		(31 "F.CrtYd" user "Package Geometry/Place Bound Top")
		(29 "B.CrtYd" user "Package Geometry/Place Bound Bottom")
		(35 "F.Fab" user "Ref Des/Assembly Top")
		(33 "B.Fab" user "Ref Des/Assembly Bottom")
	)
	(footprint ""
		(layer "F.Cu")
		(at 91.300046 -172.909992 -90)
		(property "Reference" "HDDSAS14"
			(at 0 0 270)
			(layer "F.SilkS")
			(hide yes)
			(effects
				(font
					(size 1.27 1.27)
				)
			)
		)
		(property "Value" "SKT-SAS15P-14P-45-GP"
			(at -20.7645 -8.9789 270)
			(unlocked yes)
			(layer "F.Fab")
			(hide yes)
			(effects
				(font
					(size 1.016 1.016)
					(thickness 0.1524)
				)
			)
		)
		(property "Device Type" "10120818-001C-TRLF"
			(at -20.7645 -10.5029 270)
			(unlocked yes)
			(layer "F.Fab")
			(hide yes)
			(effects
				(font
					(size 1.016 1.016)
					(thickness 0.1524)
				)
			)
		)
		(duplicate_pad_numbers_are_jumpers no)
		(fp_line
			(start 1.651 4.2926)
			(end 1.651 3.0099)
			(stroke
				(width 0.1524)
				(type default)
			)
			(layer "F.SilkS")
		)
		(fp_line
			(start 8.509 4.2926)
			(end 1.651 4.2926)
			(stroke
				(width 0.1524)
				(type default)
			)
			(layer "F.SilkS")
		)
		(fp_line
			(start -23.4188 3.0099)
			(end -23.4188 -3.2512)
			(stroke
				(width 0.1524)
				(type default)
			)
			(layer "F.SilkS")
		)
		(fp_line
			(start 1.651 3.0099)
			(end -23.4188 3.0099)
			(stroke
				(width 0.1524)
				(type default)
			)
			(layer "F.SilkS")
		)
		(fp_line
			(start 8.509 3.0099)
			(end 8.509 4.2926)
			(stroke
				(width 0.1524)
				(type default)
			)
			(layer "F.SilkS")
		)
		(fp_line
			(start 23.4188 3.0099)
			(end 8.509 3.0099)
			(stroke
				(width 0.1524)
				(type default)
			)
			(layer "F.SilkS")
		)
		(fp_line
			(start -23.4188 -3.2512)
			(end 23.4188 -3.2512)
			(stroke
				(width 0.1524)
				(type default)
			)
			(layer "F.SilkS")
		)
		(fp_line
			(start 23.4188 -3.2512)
			(end 23.4188 3.0099)
			(stroke
				(width 0.1524)
				(type default)
			)
			(layer "F.SilkS")
		)
		(fp_line
			(start 15.5067 -3.3401)
			(end 16.2687 -3.3401)
			(stroke
				(width 0.3302)
				(type default)
			)
			(layer "F.SilkS")
		)
		(fp_poly
			(pts
				(xy 15.868904 -3.230372) (xy 16.503904 -3.865372) (xy 15.233904 -3.865372)
			)
			(stroke
				(width 0)
				(type default)
			)
			(fill yes)
			(layer "F.SilkS")
		)
		(fp_poly
			(pts
				(xy -22.8727 -2.7559) (xy 22.8727 -2.7559) (xy 22.8727 2.7559) (xy 8.255 2.7559) (xy 8.255 3.5179)
				(xy 1.905 3.5179) (xy 1.905 2.7559) (xy -22.8727 2.7559)
			)
			(stroke
				(width 0)
				(type default)
			)
			(fill no)
			(layer "F.CrtYd")
		)
		(fp_poly
			(pts
				(xy 1.397 4.5466) (xy 1.397 3.2639) (xy -23.6728 3.2639) (xy -23.6728 -3.5052) (xy 23.6728 -3.5052)
				(xy 23.6728 -0.00635) (xy 22.8727 -0.00635) (xy 22.8727 -2.7559) (xy -22.8727 -2.7559) (xy -22.8727 2.7559)
				(xy 1.905 2.7559) (xy 1.905 3.5179) (xy 8.255 3.5179) (xy 8.255 2.7559) (xy 22.8727 2.7559) (xy 22.8727 0.00635)
				(xy 23.6728 0.00635) (xy 23.6728 3.2639) (xy 8.763 3.2639) (xy 8.763 4.5466)
			)
			(stroke
				(width 0)
				(type default)
			)
			(fill no)
			(layer "F.CrtYd")
		)
		(fp_poly
			(pts
				(xy 1.397 4.5466) (xy 1.397 3.2639) (xy -23.6728 3.2639) (xy -23.6728 -3.5052) (xy 23.6728 -3.5052)
				(xy 23.6728 3.2639) (xy 8.763 3.2639) (xy 8.763 4.5466)
			)
			(stroke
				(width 0)
				(type default)
			)
			(fill no)
			(layer "F.Fab")
		)
		(pad "" np_thru_hole circle
			(at -18.874994 0 270)
			(size 0.254 0.254)
			(drill 1.3462)
			(layers "*.Cu" "*.Mask")
			(clearance 0.9017)
			(thermal_gap 0.9017)
		)
		(pad "" np_thru_hole circle
			(at 18.874994 0 270)
			(size 0.254 0.254)
			(drill 0.9398)
			(layers "*.Cu" "*.Mask")
			(clearance 0.6985)
			(thermal_gap 0.6985)
		)
		(pad "G1" smd rect
			(at 21.874988 0 270)
			(size 2.5908 2.5908)
			(layers "F.Cu" "F.Mask" "F.Paste")
			(net "GND")
		)
		(pad "G2" smd rect
			(at -21.874988 0 270)
			(size 2.5908 2.5908)
			(layers "F.Cu" "F.Mask" "F.Paste")
			(net "GND")
		)
		(pad "P1" smd rect
			(at 1.905 -1.82499 270)
			(size 0.6096 2.3622)
			(layers "F.Cu" "F.Mask" "F.Paste")
			(net "Net_2146")
		)
		(pad "P2" smd rect
			(at 0.635 -1.82499 270)
			(size 0.6096 2.3622)
			(layers "F.Cu" "F.Mask" "F.Paste")
			(net "Net_2147")
		)
		(pad "P3" smd rect
			(at -0.635 -1.82499 270)
			(size 0.6096 2.3622)
			(layers "F.Cu" "F.Mask" "F.Paste")
			(net "Net_2148")
		)
		(pad "P4" smd rect
			(at -1.905 -1.82499 270)
			(size 0.6096 2.3622)
			(layers "F.Cu" "F.Mask" "F.Paste")
			(net "GND")
		)
		(pad "P5" smd rect
			(at -3.175 -1.82499 270)
			(size 0.6096 2.3622)
			(layers "F.Cu" "F.Mask" "F.Paste")
			(net "HDD_PRSNT_14")
		)
		(pad "P6" smd rect
			(at -4.445 -1.82499 270)
			(size 0.6096 2.3622)
			(layers "F.Cu" "F.Mask" "F.Paste")
			(net "GND")
		)
		(pad "P7" smd rect
			(at -5.715 -1.82499 270)
			(size 0.6096 2.3622)
			(layers "F.Cu" "F.Mask" "F.Paste")
			(net "5V_PRE_14")
		)
		(pad "P8" smd rect
			(at -6.985 -1.82499 270)
			(size 0.6096 2.3622)
			(layers "F.Cu" "F.Mask" "F.Paste")
			(net "P5V_HDD14")
		)
		(pad "P9" smd rect
			(at -8.255 -1.82499 270)
			(size 0.6096 2.3622)
			(layers "F.Cu" "F.Mask" "F.Paste")
			(net "P5V_HDD14")
		)
		(pad "P10" smd rect
			(at -9.525 -1.82499 270)
			(size 0.6096 2.3622)
			(layers "F.Cu" "F.Mask" "F.Paste")
			(net "GND")
		)
		(pad "P11" smd rect
			(at -10.795 -1.82499 270)
			(size 0.6096 2.3622)
			(layers "F.Cu" "F.Mask" "F.Paste")
			(net "ACT_HDD_14")
		)
		(pad "P12" smd rect
			(at -12.065 -1.82499 270)
			(size 0.6096 2.3622)
			(layers "F.Cu" "F.Mask" "F.Paste")
			(net "GND")
		)
		(pad "P13" smd rect
			(at -13.335 -1.82499 270)
			(size 0.6096 2.3622)
			(layers "F.Cu" "F.Mask" "F.Paste")
			(net "12V_PRE_14")
		)
		(pad "P14" smd rect
			(at -14.605 -1.82499 270)
			(size 0.6096 2.3622)
			(layers "F.Cu" "F.Mask" "F.Paste")
			(net "P12V_HDD14")
		)
		(pad "P15" smd rect
			(at -15.875 -1.82499 270)
			(size 0.6096 2.3622)
			(layers "F.Cu" "F.Mask" "F.Paste")
			(net "P12V_HDD14")
		)
		(pad "S1" smd rect
			(at 15.875 -1.82499 270)
			(size 0.6096 2.3622)
			(layers "F.Cu" "F.Mask" "F.Paste")
			(net "GND")
		)
		(pad "S2" smd rect
			(at 14.605 -1.82499 270)
			(size 0.6096 2.3622)
			(layers "F.Cu" "F.Mask" "F.Paste")
			(net "SAS_HDD_RX_P14")
		)
		(pad "S3" smd rect
			(at 13.335 -1.82499 270)
			(size 0.6096 2.3622)
			(layers "F.Cu" "F.Mask" "F.Paste")
			(net "SAS_HDD_RX_N14")
		)
		(pad "S4" smd rect
			(at 12.065 -1.82499 270)
			(size 0.6096 2.3622)
			(layers "F.Cu" "F.Mask" "F.Paste")
			(net "GND")
		)
		(pad "S5" smd rect
			(at 10.795 -1.82499 270)
			(size 0.6096 2.3622)
			(layers "F.Cu" "F.Mask" "F.Paste")
			(net "PHY_DRV_A_TO_SCC_A_14_DN")
		)
		(pad "S6" smd rect
			(at 9.525 -1.82499 270)
			(size 0.6096 2.3622)
			(layers "F.Cu" "F.Mask" "F.Paste")
			(net "PHY_DRV_A_TO_SCC_A_14_DP")
		)
		(pad "S7" smd rect
			(at 8.255 -1.82499 270)
			(size 0.6096 2.3622)
			(layers "F.Cu" "F.Mask" "F.Paste")
			(net "GND")
		)
		(pad "S8" smd rect
			(at 7.480046 2.845054 270)
			(size 0.508 2.3622)
			(layers "F.Cu" "F.Mask" "F.Paste")
			(net "GND")
		)
		(pad "S9" smd rect
			(at 6.679946 2.845054 270)
			(size 0.508 2.3622)
			(layers "F.Cu" "F.Mask" "F.Paste")
			(net "Net_451")
		)
		(pad "S10" smd rect
			(at 5.8801 2.845054 270)
			(size 0.508 2.3622)
			(layers "F.Cu" "F.Mask" "F.Paste")
			(net "Net_343")
		)
		(pad "S11" smd rect
			(at 5.08 2.845054 270)
			(size 0.508 2.3622)
			(layers "F.Cu" "F.Mask" "F.Paste")
			(net "GND")
		)
		(pad "S12" smd rect
			(at 4.2799 2.845054 270)
			(size 0.508 2.3622)
			(layers "F.Cu" "F.Mask" "F.Paste")
			(net "Net_379")
		)
		(pad "S13" smd rect
			(at 3.480054 2.845054 270)
			(size 0.508 2.3622)
			(layers "F.Cu" "F.Mask" "F.Paste")
			(net "Net_415")
		)
		(pad "S14" smd rect
			(at 2.679954 2.845054 270)
			(size 0.508 2.3622)
			(layers "F.Cu" "F.Mask" "F.Paste")
			(net "GND")
		)
		(zone
			(layer "F.Cu")
			(hatch none 0.5)
			(connect_pads
				(clearance 0)
			)
			(min_thickness 0.25)
			(keepout
				(tracks allowed)
				(vias not_allowed)
				(pads allowed)
				(copperpour not_allowed)
				(footprints allowed)
			)
			(placement
				(enabled no)
				(sheetname "")
			)
			(fill
				(thermal_gap 0.5)
				(thermal_bridge_width 0.5)
				(island_removal_mode 0)
			)
			(polygon
				(pts
					(xy 94.957646 -189.648592) (xy 87.883746 -189.648592) (xy 87.883746 -196.582792) (xy 88.988646 -196.582792)
					(xy 88.988646 -192.467992) (xy 93.611446 -192.467992) (xy 93.611446 -196.582792) (xy 94.957646 -196.582792)
				)
			)
		)
		(zone
			(layer "F.Cu")
			(hatch none 0.5)
			(connect_pads
				(clearance 0)
			)
			(min_thickness 0.25)
			(keepout
				(tracks not_allowed)
				(vias allowed)
				(pads allowed)
				(copperpour not_allowed)
				(footprints allowed)
			)
			(placement
				(enabled no)
				(sheetname "")
			)
			(fill
				(thermal_gap 0.5)
				(thermal_bridge_width 0.5)
				(island_removal_mode 0)
			)
			(polygon
				(pts
					(xy 94.957646 -189.648592) (xy 87.883746 -189.648592) (xy 87.883746 -196.582792) (xy 88.988646 -196.582792)
					(xy 88.988646 -192.467992) (xy 93.611446 -192.467992) (xy 93.611446 -196.582792) (xy 94.957646 -196.582792)
				)
			)
		)
		(zone
			(layer "F.Cu")
			(hatch none 0.5)
			(connect_pads
				(clearance 0)
			)
			(min_thickness 0.25)
			(keepout
				(tracks allowed)
				(vias not_allowed)
				(pads allowed)
				(copperpour not_allowed)
				(footprints allowed)
			)
			(placement
				(enabled no)
				(sheetname "")
			)
			(fill
				(thermal_gap 0.5)
				(thermal_bridge_width 0.5)
				(island_removal_mode 0)
			)
			(polygon
				(pts
					(xy 94.957646 -156.171392) (xy 87.883746 -156.171392) (xy 87.883746 -149.237192) (xy 88.988646 -149.237192)
					(xy 88.988646 -153.351992) (xy 93.611446 -153.351992) (xy 93.611446 -149.237192) (xy 94.957646 -149.237192)
				)
			)
		)
		(zone
			(layer "F.Cu")
			(hatch none 0.5)
			(connect_pads
				(clearance 0)
			)
			(min_thickness 0.25)
			(keepout
				(tracks not_allowed)
				(vias allowed)
				(pads allowed)
				(copperpour not_allowed)
				(footprints allowed)
			)
			(placement
				(enabled no)
				(sheetname "")
			)
			(fill
				(thermal_gap 0.5)
				(thermal_bridge_width 0.5)
				(island_removal_mode 0)
			)
			(polygon
				(pts
					(xy 94.957646 -156.171392) (xy 87.883746 -156.171392) (xy 87.883746 -149.237192) (xy 88.988646 -149.237192)
					(xy 88.988646 -153.351992) (xy 93.611446 -153.351992) (xy 93.611446 -149.237192) (xy 94.957646 -149.237192)
				)
			)
		)
		(zone
			(layers "F.Cu" "B.Cu" "In1.Cu" "In2.Cu" "In3.Cu" "In4.Cu" "In5.Cu" "In6.Cu"
				"In7.Cu" "In8.Cu" "In9.Cu" "In10.Cu"
			)
			(hatch none 0.5)
			(connect_pads
				(clearance 0)
			)
			(min_thickness 0.25)
			(keepout
				(tracks not_allowed)
				(vias allowed)
				(pads allowed)
				(copperpour not_allowed)
				(footprints allowed)
			)
			(placement
				(enabled no)
				(sheetname "")
			)
			(fill
				(thermal_gap 0.5)
				(thermal_bridge_width 0.5)
				(island_removal_mode 0)
			)
			(polygon
				(pts
					(arc
						(start 92.074746 -154.034998)
						(mid 90.525346 -154.034998)
						(end 92.074746 -154.034998)
					)
				)
			)
		)
		(zone
			(layers "F.Cu" "B.Cu" "In1.Cu" "In2.Cu" "In3.Cu" "In4.Cu" "In5.Cu" "In6.Cu"
				"In7.Cu" "In8.Cu" "In9.Cu" "In10.Cu"
			)
			(hatch none 0.5)
			(connect_pads
				(clearance 0)
			)
			(min_thickness 0.25)
			(keepout
				(tracks not_allowed)
				(vias allowed)
				(pads allowed)
				(copperpour not_allowed)
				(footprints allowed)
			)
			(placement
				(enabled no)
				(sheetname "")
			)
			(fill
				(thermal_gap 0.5)
				(thermal_bridge_width 0.5)
				(island_removal_mode 0)
			)
			(polygon
				(pts
					(arc
						(start 92.277946 -191.784986)
						(mid 90.322146 -191.784986)
						(end 92.277946 -191.784986)
					)
				)
			)
		)
	)
	(footprint ""
		(layer "F.Cu")
		(at 112.388142 -272.726404 180)
		(property "Reference" "R211"
			(at 0 0 180)
			(layer "F.SilkS")
			(hide yes)
			(effects
				(font
					(size 1.27 1.27)
				)
			)
		)
		(property "Value" "0R2J-2-GP"
			(at 0.064008 -3.993896 180)
			(unlocked yes)
			(layer "F.Fab")
			(hide yes)
			(effects
				(font
					(size 1.016 1.016)
					(thickness 0.1524)
				)
			)
		)
		(property "Device Type" "R402H16"
			(at 0.064008 -5.517896 180)
			(unlocked yes)
			(layer "F.Fab")
			(hide yes)
			(effects
				(font
					(size 1.016 1.016)
					(thickness 0.1524)
				)
			)
		)
		(duplicate_pad_numbers_are_jumpers no)
		(fp_line
			(start 0.508 -0.9398)
			(end -0.508 -0.9398)
			(stroke
				(width 0.1524)
				(type default)
			)
			(layer "F.SilkS")
		)
		(fp_line
			(start -0.508 -0.9398)
			(end -0.508 0.9398)
			(stroke
				(width 0.1524)
				(type default)
			)
			(layer "F.SilkS")
		)
		(fp_rect
			(start -0.508 0.9398)
			(end 0.508 -0.9398)
			(stroke
				(width 0)
				(type default)
			)
			(fill no)
			(layer "F.CrtYd")
		)
		(fp_rect
			(start -0.508 0.9398)
			(end 0.508 -0.9398)
			(stroke
				(width 0)
				(type default)
			)
			(fill no)
			(layer "F.Fab")
		)
		(pad "1" smd custom
			(at 0 -0.4445 180)
			(size 0.1397 0.1397)
			(layers "F.Cu" "F.Mask" "F.Paste")
			(net "DRIVE_A_3_PWR")
			(options
				(clearance outline)
				(anchor circle)
			)
			(primitives
				(gr_poly
					(pts
						(arc
							(start -0.1778 -0.2794)
							(mid -0.249642 -0.249642)
							(end -0.2794 -0.1778)
						)
						(arc
							(start -0.2794 0.1778)
							(mid -0.249642 0.249642)
							(end -0.1778 0.2794)
						)
						(arc
							(start 0.1778 0.2794)
							(mid 0.249642 0.249642)
							(end 0.2794 0.1778)
						)
						(arc
							(start 0.2794 -0.1778)
							(mid 0.249642 -0.249642)
							(end 0.1778 -0.2794)
						)
					)
					(width 0)
					(fill yes)
				)
			)
		)
		(pad "2" smd custom
			(at 0 0.4445 180)
			(size 0.1397 0.1397)
			(layers "F.Cu" "F.Mask" "F.Paste")
			(net "SW_PWR_R_HDD3")
			(options
				(clearance outline)
				(anchor circle)
			)
			(primitives
				(gr_poly
					(pts
						(arc
							(start -0.1778 -0.2794)
							(mid -0.249642 -0.249642)
							(end -0.2794 -0.1778)
						)
						(arc
							(start -0.2794 0.1778)
							(mid -0.249642 0.249642)
							(end -0.1778 0.2794)
						)
						(arc
							(start 0.1778 0.2794)
							(mid 0.249642 0.249642)
							(end 0.2794 0.1778)
						)
						(arc
							(start 0.2794 -0.1778)
							(mid 0.249642 -0.249642)
							(end 0.1778 -0.2794)
						)
					)
					(width 0)
					(fill yes)
				)
			)
		)
	)
	(footprint ""
		(layer "F.Cu")
		(at 221.0054 -177.0634)
		(property "Reference" "C134"
			(at 0 0 0)
			(layer "F.SilkS")
			(hide yes)
			(effects
				(font
					(size 1.27 1.27)
				)
			)
		)
		(property "Value" "SC22U25V6KX-2-GP-U"
			(at -2.860802 -5.279644 0)
			(unlocked yes)
			(layer "F.Fab")
			(hide yes)
			(effects
				(font
					(size 1.016 1.016)
					(thickness 0.1524)
				)
			)
		)
		(property "Device Type" "C1206-TO0D3H75"
			(at -2.860802 -6.803644 0)
			(unlocked yes)
			(layer "F.Fab")
			(hide yes)
			(effects
				(font
					(size 1.016 1.016)
					(thickness 0.1524)
				)
			)
		)
		(duplicate_pad_numbers_are_jumpers no)
		(fp_line
			(start -1.3081 -2.3749)
			(end 1.3081 -2.3749)
			(stroke
				(width 0.1524)
				(type default)
			)
			(layer "F.SilkS")
		)
		(fp_line
			(start -1.3081 2.3749)
			(end -1.3081 -2.3749)
			(stroke
				(width 0.1524)
				(type default)
			)
			(layer "F.SilkS")
		)
		(fp_line
			(start 1.3081 -2.3749)
			(end 1.3081 2.3749)
			(stroke
				(width 0.1524)
				(type default)
			)
			(layer "F.SilkS")
		)
		(fp_line
			(start 1.3081 2.3749)
			(end -1.3081 2.3749)
			(stroke
				(width 0.1524)
				(type default)
			)
			(layer "F.SilkS")
		)
		(fp_rect
			(start -0.8001 1.6002)
			(end 0.8001 -1.6002)
			(stroke
				(width 0)
				(type default)
			)
			(fill no)
			(layer "F.CrtYd")
		)
		(fp_poly
			(pts
				(xy -1.5621 2.4511) (xy -1.5621 1.6002) (xy 0.8001 1.6002) (xy 0.8001 -1.6002) (xy -0.8001 -1.6002)
				(xy -0.8001 1.5875) (xy -1.5621 1.5875) (xy -1.5621 -2.4511) (xy 1.5621 -2.4511) (xy 1.5621 2.4511)
			)
			(stroke
				(width 0)
				(type default)
			)
			(fill no)
			(layer "F.CrtYd")
		)
		(fp_rect
			(start -1.5621 2.4511)
			(end 1.5621 -2.4511)
			(stroke
				(width 0)
				(type default)
			)
			(fill no)
			(layer "F.Fab")
		)
		(pad "1" smd rect
			(at 0 -1.392936)
			(size 2.1082 1.4478)
			(layers "F.Cu" "F.Mask" "F.Paste")
			(net "P12V_A_COMP")
		)
		(pad "2" smd rect
			(at 0 1.392936)
			(size 2.1082 1.4478)
			(layers "F.Cu" "F.Mask" "F.Paste")
			(net "GND")
		)
	)
)
